(kicad_pcb
	(version 20260206)
	(generator "pcbnew")
	(generator_version "10.0")
	(general
		(thickness 1.6)
		(legacy_teardrops no)
	)
	(paper "A4")
	(title_block
		(title "01162023_DA0F0TEBIF0_F0T_Expander_BD_F_brd_V02_OCP.brd")
		(comment 1 "Grand Teton / footprints 4370-4376 of 9728")
	)
	(layers
		(0 "F.Cu" signal "TOP")
		(4 "In1.Cu" signal "GND")
		(6 "In2.Cu" signal "VCC")
		(8 "In3.Cu" signal "VCC1")
		(10 "In4.Cu" signal "GND1")
		(12 "In5.Cu" signal "IN1")
		(14 "In6.Cu" signal "GND2")
		(16 "In7.Cu" signal "IN2")
		(18 "In8.Cu" signal "GND3")
		(20 "In9.Cu" signal "IN3")
		(22 "In10.Cu" signal "GND4")
		(24 "In11.Cu" signal "IN4")
		(26 "In12.Cu" signal "GND5")
		(28 "In13.Cu" signal "IN5")
		(30 "In14.Cu" signal "GND6")
		(32 "In15.Cu" signal "IN6")
		(34 "In16.Cu" signal "GND7")
		(2 "B.Cu" signal "BOTTOM")
		(9 "F.Adhes" user "F.Adhesive")
		(11 "B.Adhes" user "B.Adhesive")
		(13 "F.Paste" user "Package Geometry/Pastemask Top")
		(15 "B.Paste" user "Package Geometry/Pastemask Bottom")
		(5 "F.SilkS" user "Ref Des/Silkscreen Top")
		(7 "B.SilkS" user "Ref Des/Silkscreen Bottom")
		(1 "F.Mask" user "Board Geometry/Soldermask Top")
		(3 "B.Mask" user "Board Geometry/Soldermask Bottom")
		(17 "Dwgs.User" user "User.Drawings")
		(19 "Cmts.User" user "User.Comments")
		(21 "Eco1.User" user "User.Eco1")
		(23 "Eco2.User" user "User.Eco2")
		(25 "Edge.Cuts" user "Board Geometry/Outline")
		(27 "Margin" user)
		(31 "F.CrtYd" user "Package Geometry/Place Bound Top")
		(29 "B.CrtYd" user "Package Geometry/Place Bound Bottom")
		(35 "F.Fab" user "Ref Des/Assembly Top")
		(33 "B.Fab" user "Ref Des/Assembly Bottom")
	)
	(footprint ""
		(layer "F.Cu")
		(at 215.006936 -188.652404 90)
		(property "Reference" "R5415"
			(at 0 0 90)
			(layer "F.SilkS")
			(hide yes)
			(effects
				(font
					(size 1.27 1.27)
				)
			)
		)
		(property "Value" ""
			(at 0 0 90)
			(layer "F.Fab")
			(effects
				(font
					(size 1.27 1.27)
				)
			)
		)
		(duplicate_pad_numbers_are_jumpers no)
		(fp_line
			(start 0.7874 -0.4064)
			(end 0.7874 0.4064)
			(stroke
				(width 0.1524)
				(type default)
			)
			(layer "F.SilkS")
		)
		(fp_line
			(start -0.7874 -0.4064)
			(end 0.7874 -0.4064)
			(stroke
				(width 0.1524)
				(type default)
			)
			(layer "F.SilkS")
		)
		(fp_line
			(start 0.7874 0.4064)
			(end -0.7874 0.4064)
			(stroke
				(width 0.1524)
				(type default)
			)
			(layer "F.SilkS")
		)
		(fp_line
			(start -0.7874 0.4064)
			(end -0.7874 -0.4064)
			(stroke
				(width 0.1524)
				(type default)
			)
			(layer "F.SilkS")
		)
		(fp_line
			(start -0.12065 -0.305054)
			(end -0.12065 -0.2794)
			(stroke
				(width 0.1)
				(type default)
			)
			(layer "F.Fab")
		)
		(fp_line
			(start -0.67945 -0.305054)
			(end -0.12065 -0.305054)
			(stroke
				(width 0.1)
				(type default)
			)
			(layer "F.Fab")
		)
		(fp_line
			(start 0.67945 -0.3048)
			(end 0.67945 0.3048)
			(stroke
				(width 0.1)
				(type default)
			)
			(layer "F.Fab")
		)
		(fp_line
			(start 0.12065 -0.3048)
			(end 0.67945 -0.3048)
			(stroke
				(width 0.1)
				(type default)
			)
			(layer "F.Fab")
		)
		(fp_line
			(start 0.12065 -0.2794)
			(end 0.12065 -0.3048)
			(stroke
				(width 0.1)
				(type default)
			)
			(layer "F.Fab")
		)
		(fp_line
			(start -0.12065 -0.2794)
			(end 0.12065 -0.2794)
			(stroke
				(width 0.1)
				(type default)
			)
			(layer "F.Fab")
		)
		(fp_line
			(start 0.120396 0.2794)
			(end -0.12065 0.2794)
			(stroke
				(width 0.1)
				(type default)
			)
			(layer "F.Fab")
		)
		(fp_line
			(start -0.12065 0.2794)
			(end -0.12065 0.3048)
			(stroke
				(width 0.1)
				(type default)
			)
			(layer "F.Fab")
		)
		(fp_line
			(start 0.67945 0.3048)
			(end 0.120396 0.3048)
			(stroke
				(width 0.1)
				(type default)
			)
			(layer "F.Fab")
		)
		(fp_line
			(start 0.120396 0.3048)
			(end 0.120396 0.2794)
			(stroke
				(width 0.1)
				(type default)
			)
			(layer "F.Fab")
		)
		(fp_line
			(start -0.12065 0.3048)
			(end -0.67945 0.3048)
			(stroke
				(width 0.1)
				(type default)
			)
			(layer "F.Fab")
		)
		(fp_line
			(start -0.67945 0.3048)
			(end -0.67945 -0.305054)
			(stroke
				(width 0.1)
				(type default)
			)
			(layer "F.Fab")
		)
		(pad "1" smd circle
			(at -0.40005 0 90)
			(size 0 0)
			(layers "F.Cu" "F.Mask" "F.Paste")
			(net "BIC_SEL_FLASH_SW1_R")
		)
		(pad "2" smd circle
			(at 0.40005 0 90)
			(size 0 0)
			(layers "F.Cu" "F.Mask" "F.Paste")
			(net "GND")
		)
	)
	(footprint ""
		(layer "F.Cu")
		(at 359.156 -177.038)
		(property "Reference" "R4669"
			(at 0 0 0)
			(layer "F.SilkS")
			(hide yes)
			(effects
				(font
					(size 1.27 1.27)
				)
			)
		)
		(property "Value" ""
			(at 0 0 0)
			(layer "F.Fab")
			(effects
				(font
					(size 1.27 1.27)
				)
			)
		)
		(duplicate_pad_numbers_are_jumpers no)
		(fp_line
			(start -0.7874 -0.4064)
			(end 0.7874 -0.4064)
			(stroke
				(width 0.1524)
				(type default)
			)
			(layer "F.SilkS")
		)
		(fp_line
			(start -0.7874 0.4064)
			(end -0.7874 -0.4064)
			(stroke
				(width 0.1524)
				(type default)
			)
			(layer "F.SilkS")
		)
		(fp_line
			(start 0.7874 -0.4064)
			(end 0.7874 0.4064)
			(stroke
				(width 0.1524)
				(type default)
			)
			(layer "F.SilkS")
		)
		(fp_line
			(start 0.7874 0.4064)
			(end -0.7874 0.4064)
			(stroke
				(width 0.1524)
				(type default)
			)
			(layer "F.SilkS")
		)
		(fp_line
			(start -0.67945 -0.305054)
			(end -0.12065 -0.305054)
			(stroke
				(width 0.1)
				(type default)
			)
			(layer "F.Fab")
		)
		(fp_line
			(start -0.67945 0.3048)
			(end -0.67945 -0.305054)
			(stroke
				(width 0.1)
				(type default)
			)
			(layer "F.Fab")
		)
		(fp_line
			(start -0.12065 -0.305054)
			(end -0.12065 -0.2794)
			(stroke
				(width 0.1)
				(type default)
			)
			(layer "F.Fab")
		)
		(fp_line
			(start -0.12065 -0.2794)
			(end 0.12065 -0.2794)
			(stroke
				(width 0.1)
				(type default)
			)
			(layer "F.Fab")
		)
		(fp_line
			(start -0.12065 0.2794)
			(end -0.12065 0.3048)
			(stroke
				(width 0.1)
				(type default)
			)
			(layer "F.Fab")
		)
		(fp_line
			(start -0.12065 0.3048)
			(end -0.67945 0.3048)
			(stroke
				(width 0.1)
				(type default)
			)
			(layer "F.Fab")
		)
		(fp_line
			(start 0.120396 0.2794)
			(end -0.12065 0.2794)
			(stroke
				(width 0.1)
				(type default)
			)
			(layer "F.Fab")
		)
		(fp_line
			(start 0.120396 0.3048)
			(end 0.120396 0.2794)
			(stroke
				(width 0.1)
				(type default)
			)
			(layer "F.Fab")
		)
		(fp_line
			(start 0.12065 -0.3048)
			(end 0.67945 -0.3048)
			(stroke
				(width 0.1)
				(type default)
			)
			(layer "F.Fab")
		)
		(fp_line
			(start 0.12065 -0.2794)
			(end 0.12065 -0.3048)
			(stroke
				(width 0.1)
				(type default)
			)
			(layer "F.Fab")
		)
		(fp_line
			(start 0.67945 -0.3048)
			(end 0.67945 0.3048)
			(stroke
				(width 0.1)
				(type default)
			)
			(layer "F.Fab")
		)
		(fp_line
			(start 0.67945 0.3048)
			(end 0.120396 0.3048)
			(stroke
				(width 0.1)
				(type default)
			)
			(layer "F.Fab")
		)
		(pad "1" smd circle
			(at -0.40005 0)
			(size 0 0)
			(layers "F.Cu" "F.Mask" "F.Paste")
			(net "P3V3_AUX")
		)
		(pad "2" smd circle
			(at 0.40005 0)
			(size 0 0)
			(layers "F.Cu" "F.Mask" "F.Paste")
			(net "RST_PEX_SSD6_PERST_R_N")
		)
	)
	(footprint ""
		(layer "F.Cu")
		(at 9.446768 -152.859994 180)
		(property "Reference" "PR6865"
			(at 0 0 180)
			(layer "F.SilkS")
			(hide yes)
			(effects
				(font
					(size 1.27 1.27)
				)
			)
		)
		(property "Value" ""
			(at 0 0 180)
			(layer "F.Fab")
			(effects
				(font
					(size 1.27 1.27)
				)
			)
		)
		(duplicate_pad_numbers_are_jumpers no)
		(fp_line
			(start 1.2954 0.5842)
			(end -1.2954 0.5842)
			(stroke
				(width 0.1524)
				(type default)
			)
			(layer "F.SilkS")
		)
		(fp_line
			(start 1.2954 -0.5842)
			(end 1.2954 0.5842)
			(stroke
				(width 0.1524)
				(type default)
			)
			(layer "F.SilkS")
		)
		(fp_line
			(start -1.2954 0.5842)
			(end -1.2954 -0.5842)
			(stroke
				(width 0.1524)
				(type default)
			)
			(layer "F.SilkS")
		)
		(fp_line
			(start -1.2954 -0.5842)
			(end 1.2954 -0.5842)
			(stroke
				(width 0.1524)
				(type default)
			)
			(layer "F.SilkS")
		)
		(fp_line
			(start 1.1938 0.4064)
			(end 0.8636 0.4064)
			(stroke
				(width 0.1)
				(type default)
			)
			(layer "F.Fab")
		)
		(fp_line
			(start 1.1938 -0.406654)
			(end 1.1938 0.4064)
			(stroke
				(width 0.1)
				(type default)
			)
			(layer "F.Fab")
		)
		(fp_line
			(start 0.8636 0.4572)
			(end -0.8636 0.4572)
			(stroke
				(width 0.1)
				(type default)
			)
			(layer "F.Fab")
		)
		(fp_line
			(start 0.8636 0.4064)
			(end 0.8636 0.4572)
			(stroke
				(width 0.1)
				(type default)
			)
			(layer "F.Fab")
		)
		(fp_line
			(start 0.8636 -0.406654)
			(end 1.1938 -0.406654)
			(stroke
				(width 0.1)
				(type default)
			)
			(layer "F.Fab")
		)
		(fp_line
			(start 0.8636 -0.4572)
			(end 0.8636 -0.406654)
			(stroke
				(width 0.1)
				(type default)
			)
			(layer "F.Fab")
		)
		(fp_line
			(start -0.8636 0.4572)
			(end -0.8636 0.4318)
			(stroke
				(width 0.1)
				(type default)
			)
			(layer "F.Fab")
		)
		(fp_line
			(start -0.8636 0.4318)
			(end -0.8636 0.4064)
			(stroke
				(width 0.1)
				(type default)
			)
			(layer "F.Fab")
		)
		(fp_line
			(start -0.8636 0.4064)
			(end -1.1938 0.4064)
			(stroke
				(width 0.1)
				(type default)
			)
			(layer "F.Fab")
		)
		(fp_line
			(start -0.8636 -0.406654)
			(end -0.8636 -0.4572)
			(stroke
				(width 0.1)
				(type default)
			)
			(layer "F.Fab")
		)
		(fp_line
			(start -0.8636 -0.4572)
			(end 0.8636 -0.4572)
			(stroke
				(width 0.1)
				(type default)
			)
			(layer "F.Fab")
		)
		(fp_line
			(start -1.1938 0.4064)
			(end -1.1938 -0.406654)
			(stroke
				(width 0.1)
				(type default)
			)
			(layer "F.Fab")
		)
		(fp_line
			(start -1.1938 -0.406654)
			(end -0.8636 -0.406654)
			(stroke
				(width 0.1)
				(type default)
			)
			(layer "F.Fab")
		)
		(pad "1" smd rect
			(at -0.7366 0 90)
			(size 0.7112 0.8128)
			(layers "F.Cu" "F.Mask" "F.Paste")
			(net "P12V_NIC0_CO_AVIN_PD")
		)
		(pad "2" smd rect
			(at 0.7366 0 90)
			(size 0.7112 0.8128)
			(layers "F.Cu" "F.Mask" "F.Paste")
			(net "P12V_AUX")
		)
	)
	(footprint ""
		(layer "F.Cu")
		(at 220.676978 -266.873228 180)
		(property "Reference" "R6131"
			(at 0 0 180)
			(layer "F.SilkS")
			(hide yes)
			(effects
				(font
					(size 1.27 1.27)
				)
			)
		)
		(property "Value" ""
			(at 0 0 180)
			(layer "F.Fab")
			(effects
				(font
					(size 1.27 1.27)
				)
			)
		)
		(duplicate_pad_numbers_are_jumpers no)
		(fp_line
			(start 2.576322 1.1303)
			(end -2.576322 1.1303)
			(stroke
				(width 0.1524)
				(type default)
			)
			(layer "F.SilkS")
		)
		(fp_line
			(start 2.576322 -1.1303)
			(end 2.576322 1.1303)
			(stroke
				(width 0.1524)
				(type default)
			)
			(layer "F.SilkS")
		)
		(fp_line
			(start -2.576322 1.1303)
			(end -2.576322 -1.1303)
			(stroke
				(width 0.1524)
				(type default)
			)
			(layer "F.SilkS")
		)
		(fp_line
			(start -2.576322 -1.1303)
			(end 2.576322 -1.1303)
			(stroke
				(width 0.1524)
				(type default)
			)
			(layer "F.SilkS")
		)
		(fp_line
			(start 1.649984 0.899922)
			(end 1.649984 -0.899922)
			(stroke
				(width 0.1)
				(type default)
			)
			(layer "F.Fab")
		)
		(fp_line
			(start 1.649984 -0.899922)
			(end -1.649984 -0.899922)
			(stroke
				(width 0.1)
				(type default)
			)
			(layer "F.Fab")
		)
		(fp_line
			(start -1.649984 0.899922)
			(end 1.649984 0.899922)
			(stroke
				(width 0.1)
				(type default)
			)
			(layer "F.Fab")
		)
		(fp_line
			(start -1.649984 -0.899922)
			(end -1.649984 0.899922)
			(stroke
				(width 0.1)
				(type default)
			)
			(layer "F.Fab")
		)
		(pad "1A" smd rect
			(at -1.700022 0 180)
			(size 1.4986 2.0066)
			(layers "F.Cu" "F.Mask" "F.Paste")
			(net "P1V25_PEX1")
		)
		(pad "1B" smd rect
			(at -1.077722 0 180)
			(size 0.254 0.508)
			(layers "F.Cu" "F.Mask" "F.Paste")
			(net "P1V25_PEX1")
		)
		(pad "2A" smd rect
			(at 1.700022 0 180)
			(size 1.4986 2.0066)
			(layers "F.Cu" "F.Mask" "F.Paste")
			(net "P1V25_SERDES_VDDPLL_PEX1")
		)
		(pad "2B" smd rect
			(at 1.077722 0 180)
			(size 0.254 0.508)
			(layers "F.Cu" "F.Mask" "F.Paste")
			(net "P1V25_SERDES_VDDPLL_PEX1")
		)
	)
	(footprint ""
		(layer "F.Cu")
		(at 30.153356 -281.789632)
		(property "Reference" "L96"
			(at 0 0 0)
			(layer "F.SilkS")
			(hide yes)
			(effects
				(font
					(size 1.27 1.27)
				)
			)
		)
		(property "Value" ""
			(at 0 0 0)
			(layer "F.Fab")
			(effects
				(font
					(size 1.27 1.27)
				)
			)
		)
		(duplicate_pad_numbers_are_jumpers no)
		(fp_line
			(start -1.63576 -0.8128)
			(end -1.63576 0.8128)
			(stroke
				(width 0.1524)
				(type default)
			)
			(layer "F.SilkS")
		)
		(fp_line
			(start -1.63576 -0.8128)
			(end 1.63576 -0.8128)
			(stroke
				(width 0.1524)
				(type default)
			)
			(layer "F.SilkS")
		)
		(fp_line
			(start 1.63576 -0.8128)
			(end 1.63576 0.8128)
			(stroke
				(width 0.1524)
				(type default)
			)
			(layer "F.SilkS")
		)
		(fp_line
			(start 1.63576 0.8128)
			(end -1.63576 0.8128)
			(stroke
				(width 0.1524)
				(type default)
			)
			(layer "F.SilkS")
		)
		(fp_line
			(start -1.56083 -0.738632)
			(end -1.56083 0.7366)
			(stroke
				(width 0.1)
				(type default)
			)
			(layer "F.Fab")
		)
		(fp_line
			(start -1.56083 0.7366)
			(end -1.524 0.7366)
			(stroke
				(width 0.1)
				(type default)
			)
			(layer "F.Fab")
		)
		(fp_line
			(start -1.524 0.7366)
			(end 1.524 0.7366)
			(stroke
				(width 0.1)
				(type default)
			)
			(layer "F.Fab")
		)
		(fp_line
			(start 1.524 0.7366)
			(end 1.560576 0.7366)
			(stroke
				(width 0.1)
				(type default)
			)
			(layer "F.Fab")
		)
		(fp_line
			(start 1.560576 -0.738632)
			(end -1.56083 -0.738632)
			(stroke
				(width 0.1)
				(type default)
			)
			(layer "F.Fab")
		)
		(fp_line
			(start 1.560576 0.7366)
			(end 1.560576 -0.738632)
			(stroke
				(width 0.1)
				(type default)
			)
			(layer "F.Fab")
		)
		(pad "1" smd rect
			(at -0.94996 0 180)
			(size 1.1176 1.3716)
			(layers "F.Cu" "F.Mask" "F.Paste")
			(net "P1V8_PLL0_PEX0")
		)
		(pad "2" smd rect
			(at 0.94996 0 180)
			(size 1.1176 1.3716)
			(layers "F.Cu" "F.Mask" "F.Paste")
			(net "SYSPLL_VDDA18_PEX0")
		)
	)
	(footprint ""
		(layer "F.Cu")
		(at 32.31769 -113.558574 -90)
		(property "Reference" "C3998"
			(at 0 0 270)
			(layer "F.SilkS")
			(hide yes)
			(effects
				(font
					(size 1.27 1.27)
				)
			)
		)
		(property "Value" ""
			(at 0 0 270)
			(layer "F.Fab")
			(effects
				(font
					(size 1.27 1.27)
				)
			)
		)
		(duplicate_pad_numbers_are_jumpers no)
		(fp_line
			(start -0.7874 0.4064)
			(end -0.7874 -0.4064)
			(stroke
				(width 0.1524)
				(type default)
			)
			(layer "F.SilkS")
		)
		(fp_line
			(start 0.7874 0.4064)
			(end -0.7874 0.4064)
			(stroke
				(width 0.1524)
				(type default)
			)
			(layer "F.SilkS")
		)
		(fp_line
			(start -0.7874 -0.4064)
			(end 0.7874 -0.4064)
			(stroke
				(width 0.1524)
				(type default)
			)
			(layer "F.SilkS")
		)
		(fp_line
			(start 0.7874 -0.4064)
			(end 0.7874 0.4064)
			(stroke
				(width 0.1524)
				(type default)
			)
			(layer "F.SilkS")
		)
		(fp_line
			(start -0.67945 0.3048)
			(end -0.67945 -0.305054)
			(stroke
				(width 0.1)
				(type default)
			)
			(layer "F.Fab")
		)
		(fp_line
			(start -0.12065 0.3048)
			(end -0.67945 0.3048)
			(stroke
				(width 0.1)
				(type default)
			)
			(layer "F.Fab")
		)
		(fp_line
			(start 0.120396 0.3048)
			(end 0.120396 0.2794)
			(stroke
				(width 0.1)
				(type default)
			)
			(layer "F.Fab")
		)
		(fp_line
			(start 0.67945 0.3048)
			(end 0.120396 0.3048)
			(stroke
				(width 0.1)
				(type default)
			)
			(layer "F.Fab")
		)
		(fp_line
			(start -0.12065 0.2794)
			(end -0.12065 0.3048)
			(stroke
				(width 0.1)
				(type default)
			)
			(layer "F.Fab")
		)
		(fp_line
			(start 0.120396 0.2794)
			(end -0.12065 0.2794)
			(stroke
				(width 0.1)
				(type default)
			)
			(layer "F.Fab")
		)
		(fp_line
			(start -0.12065 -0.2794)
			(end 0.12065 -0.2794)
			(stroke
				(width 0.1)
				(type default)
			)
			(layer "F.Fab")
		)
		(fp_line
			(start 0.12065 -0.2794)
			(end 0.12065 -0.3048)
			(stroke
				(width 0.1)
				(type default)
			)
			(layer "F.Fab")
		)
		(fp_line
			(start 0.12065 -0.3048)
			(end 0.67945 -0.3048)
			(stroke
				(width 0.1)
				(type default)
			)
			(layer "F.Fab")
		)
		(fp_line
			(start 0.67945 -0.3048)
			(end 0.67945 0.3048)
			(stroke
				(width 0.1)
				(type default)
			)
			(layer "F.Fab")
		)
		(fp_line
			(start -0.67945 -0.305054)
			(end -0.12065 -0.305054)
			(stroke
				(width 0.1)
				(type default)
			)
			(layer "F.Fab")
		)
		(fp_line
			(start -0.12065 -0.305054)
			(end -0.12065 -0.2794)
			(stroke
				(width 0.1)
				(type default)
			)
			(layer "F.Fab")
		)
		(pad "1" smd circle
			(at -0.40005 0 270)
			(size 0 0)
			(layers "F.Cu" "F.Mask" "F.Paste")
			(net "PRSNT_NIC0_R_N")
		)
		(pad "2" smd circle
			(at 0.40005 0 270)
			(size 0 0)
			(layers "F.Cu" "F.Mask" "F.Paste")
			(net "GND")
		)
	)
	(footprint ""
		(layer "F.Cu")
		(at 16.820896 -119.140986 90)
		(property "Reference" "PC660"
			(at 0 0 90)
			(layer "F.SilkS")
			(hide yes)
			(effects
				(font
					(size 1.27 1.27)
				)
			)
		)
		(property "Value" ""
			(at 0 0 90)
			(layer "F.Fab")
			(effects
				(font
					(size 1.27 1.27)
				)
			)
		)
		(duplicate_pad_numbers_are_jumpers no)
		(fp_line
			(start 0.7874 -0.4064)
			(end 0.7874 0.4064)
			(stroke
				(width 0.1524)
				(type default)
			)
			(layer "F.SilkS")
		)
		(fp_line
			(start -0.7874 -0.4064)
			(end 0.7874 -0.4064)
			(stroke
				(width 0.1524)
				(type default)
			)
			(layer "F.SilkS")
		)
		(fp_line
			(start 0.7874 0.4064)
			(end -0.7874 0.4064)
			(stroke
				(width 0.1524)
				(type default)
			)
			(layer "F.SilkS")
		)
		(fp_line
			(start -0.7874 0.4064)
			(end -0.7874 -0.4064)
			(stroke
				(width 0.1524)
				(type default)
			)
			(layer "F.SilkS")
		)
		(fp_line
			(start -0.12065 -0.305054)
			(end -0.12065 -0.2794)
			(stroke
				(width 0.1)
				(type default)
			)
			(layer "F.Fab")
		)
		(fp_line
			(start -0.67945 -0.305054)
			(end -0.12065 -0.305054)
			(stroke
				(width 0.1)
				(type default)
			)
			(layer "F.Fab")
		)
		(fp_line
			(start 0.67945 -0.3048)
			(end 0.67945 0.3048)
			(stroke
				(width 0.1)
				(type default)
			)
			(layer "F.Fab")
		)
		(fp_line
			(start 0.12065 -0.3048)
			(end 0.67945 -0.3048)
			(stroke
				(width 0.1)
				(type default)
			)
			(layer "F.Fab")
		)
		(fp_line
			(start 0.12065 -0.2794)
			(end 0.12065 -0.3048)
			(stroke
				(width 0.1)
				(type default)
			)
			(layer "F.Fab")
		)
		(fp_line
			(start -0.12065 -0.2794)
			(end 0.12065 -0.2794)
			(stroke
				(width 0.1)
				(type default)
			)
			(layer "F.Fab")
		)
		(fp_line
			(start 0.120396 0.2794)
			(end -0.12065 0.2794)
			(stroke
				(width 0.1)
				(type default)
			)
			(layer "F.Fab")
		)
		(fp_line
			(start -0.12065 0.2794)
			(end -0.12065 0.3048)
			(stroke
				(width 0.1)
				(type default)
			)
			(layer "F.Fab")
		)
		(fp_line
			(start 0.67945 0.3048)
			(end 0.120396 0.3048)
			(stroke
				(width 0.1)
				(type default)
			)
			(layer "F.Fab")
		)
		(fp_line
			(start 0.120396 0.3048)
			(end 0.120396 0.2794)
			(stroke
				(width 0.1)
				(type default)
			)
			(layer "F.Fab")
		)
		(fp_line
			(start -0.12065 0.3048)
			(end -0.67945 0.3048)
			(stroke
				(width 0.1)
				(type default)
			)
			(layer "F.Fab")
		)
		(fp_line
			(start -0.67945 0.3048)
			(end -0.67945 -0.305054)
			(stroke
				(width 0.1)
				(type default)
			)
			(layer "F.Fab")
		)
		(pad "1" smd circle
			(at -0.40005 0 90)
			(size 0 0)
			(layers "F.Cu" "F.Mask" "F.Paste")
			(net "P3V3_NIC0_CO_GATE")
		)
		(pad "2" smd circle
			(at 0.40005 0 90)
			(size 0 0)
			(layers "F.Cu" "F.Mask" "F.Paste")
			(net "GND")
		)
	)
)
